(kicad_pcb
	(version 20260206)
	(generator "pcbnew")
	(generator_version "10.0")
	(general
		(thickness 1.6)
		(legacy_teardrops no)
	)
	(paper "A4")
	(title_block
		(title "peb — Lightning_PEB_BRD.brd")
		(comment 1 "Lightning (Wiwynn / Facebook NVMe JBOF) / footprints 203-208 of 2563")
	)
	(layers
		(0 "F.Cu" signal "TOP")
		(4 "In1.Cu" signal "L2GND")
		(6 "In2.Cu" signal "L3")
		(8 "In3.Cu" signal "L4VCC")
		(10 "In4.Cu" signal "L5VCC")
		(12 "In5.Cu" signal "L6")
		(14 "In6.Cu" signal "L7GND")
		(2 "B.Cu" signal "BOTTOM")
		(9 "F.Adhes" user "F.Adhesive")
		(11 "B.Adhes" user "B.Adhesive")
		(13 "F.Paste" user "Package Geometry/Pastemask Top")
		(15 "B.Paste" user "Package Geometry/Pastemask Bottom")
		(5 "F.SilkS" user "Ref Des/Silkscreen Top")
		(7 "B.SilkS" user "Ref Des/Silkscreen Bottom")
		(1 "F.Mask" user "Board Geometry/Soldermask Top")
		(3 "B.Mask" user "Board Geometry/Soldermask Bottom")
		(17 "Dwgs.User" user "User.Drawings")
		(19 "Cmts.User" user "User.Comments")
		(21 "Eco1.User" user "User.Eco1")
		(23 "Eco2.User" user "User.Eco2")
		(25 "Edge.Cuts" user "Board Geometry/Outline")
		(27 "Margin" user)
		(31 "F.CrtYd" user "Package Geometry/Place Bound Top")
		(29 "B.CrtYd" user "Package Geometry/Place Bound Bottom")
		(35 "F.Fab" user "Ref Des/Assembly Top")
		(33 "B.Fab" user "Ref Des/Assembly Bottom")
	)
	(footprint ""
		(layer "F.Cu")
		(at 145.8722 -33.52292)
		(property "Reference" "C390"
			(at 0 0 0)
			(layer "F.SilkS")
			(hide yes)
			(effects
				(font
					(size 1.27 1.27)
				)
			)
		)
		(property "Value" "SCD22U10V2KX-1GP"
			(at 1.1811 -2.7051 0)
			(unlocked yes)
			(layer "F.Fab")
			(hide yes)
			(effects
				(font
					(size 1.016 1.016)
					(thickness 0.1524)
				)
			)
		)
		(property "Device Type" "C402H22"
			(at 1.1811 -4.2291 0)
			(unlocked yes)
			(layer "F.Fab")
			(hide yes)
			(effects
				(font
					(size 1.016 1.016)
					(thickness 0.1524)
				)
			)
		)
		(duplicate_pad_numbers_are_jumpers no)
		(fp_rect
			(start -0.4318 0.9525)
			(end 0.4318 -0.9525)
			(stroke
				(width 0)
				(type default)
			)
			(fill no)
			(layer "F.CrtYd")
		)
		(fp_rect
			(start -0.4318 0.9525)
			(end 0.4318 -0.9525)
			(stroke
				(width 0)
				(type default)
			)
			(fill no)
			(layer "F.Fab")
		)
		(pad "1" smd custom
			(at 0 -0.4445)
			(size 0.1524 0.1524)
			(layers "F.Cu" "F.Mask" "F.Paste")
			(net "PCIE_TX_CAP_P85")
			(options
				(clearance outline)
				(anchor circle)
			)
			(primitives
				(gr_poly
					(pts
						(arc
							(start 0.3048 -0.2032)
							(mid 0.275042 -0.275042)
							(end 0.2032 -0.3048)
						)
						(arc
							(start -0.2032 -0.3048)
							(mid -0.275042 -0.275042)
							(end -0.3048 -0.2032)
						)
						(arc
							(start -0.3048 0.2032)
							(mid -0.275042 0.275042)
							(end -0.2032 0.3048)
						)
						(arc
							(start 0.2032 0.3048)
							(mid 0.275042 0.275042)
							(end 0.3048 0.2032)
						)
					)
					(width 0)
					(fill yes)
				)
			)
		)
		(pad "2" smd custom
			(at 0 0.4445)
			(size 0.1524 0.1524)
			(layers "F.Cu" "F.Mask" "F.Paste")
			(net "PCIE_TX_P85")
			(options
				(clearance outline)
				(anchor circle)
			)
			(primitives
				(gr_poly
					(pts
						(arc
							(start 0.3048 -0.2032)
							(mid 0.275042 -0.275042)
							(end 0.2032 -0.3048)
						)
						(arc
							(start -0.2032 -0.3048)
							(mid -0.275042 -0.275042)
							(end -0.3048 -0.2032)
						)
						(arc
							(start -0.3048 0.2032)
							(mid -0.275042 0.275042)
							(end -0.2032 0.3048)
						)
						(arc
							(start 0.2032 0.3048)
							(mid 0.275042 0.275042)
							(end 0.3048 0.2032)
						)
					)
					(width 0)
					(fill yes)
				)
			)
		)
	)
	(footprint ""
		(layer "F.Cu")
		(at 52.578 -184.15 90)
		(property "Reference" "C711"
			(at 0 0 90)
			(layer "F.SilkS")
			(hide yes)
			(effects
				(font
					(size 1.27 1.27)
				)
			)
		)
		(property "Value" "SC220P50V3JN-GP"
			(at 0 -2.8194 90)
			(unlocked yes)
			(layer "F.Fab")
			(hide yes)
			(effects
				(font
					(size 1.016 1.016)
					(thickness 0.1524)
				)
			)
		)
		(property "Device Type" "C603H36"
			(at 0 -4.3434 90)
			(unlocked yes)
			(layer "F.Fab")
			(hide yes)
			(effects
				(font
					(size 1.016 1.016)
					(thickness 0.1524)
				)
			)
		)
		(duplicate_pad_numbers_are_jumpers no)
		(fp_line
			(start 0.508 0)
			(end -0.508 0)
			(stroke
				(width 0.2032)
				(type default)
			)
			(layer "F.SilkS")
		)
		(fp_rect
			(start -0.5842 1.3335)
			(end 0.5842 -1.3335)
			(stroke
				(width 0)
				(type default)
			)
			(fill no)
			(layer "F.CrtYd")
		)
		(fp_rect
			(start -0.5842 1.3335)
			(end 0.5842 -1.3335)
			(stroke
				(width 0)
				(type default)
			)
			(fill no)
			(layer "F.Fab")
		)
		(pad "1" smd custom
			(at 0 -0.762 90)
			(size 0.2159 0.2159)
			(layers "F.Cu" "F.Mask" "F.Paste")
			(net "BUF_I2C8_CLKBUF1_SCL_R")
			(options
				(clearance outline)
				(anchor circle)
			)
			(primitives
				(gr_poly
					(pts
						(arc
							(start -0.3302 -0.4318)
							(mid -0.402042 -0.402042)
							(end -0.4318 -0.3302)
						)
						(arc
							(start -0.4318 0.3302)
							(mid -0.402042 0.402042)
							(end -0.3302 0.4318)
						)
						(arc
							(start 0.3302 0.4318)
							(mid 0.402042 0.402042)
							(end 0.4318 0.3302)
						)
						(arc
							(start 0.4318 -0.3302)
							(mid 0.402042 -0.402042)
							(end 0.3302 -0.4318)
						)
					)
					(width 0)
					(fill yes)
				)
			)
		)
		(pad "2" smd custom
			(at 0 0.762 90)
			(size 0.2159 0.2159)
			(layers "F.Cu" "F.Mask" "F.Paste")
			(net "GND")
			(options
				(clearance outline)
				(anchor circle)
			)
			(primitives
				(gr_poly
					(pts
						(arc
							(start -0.3302 -0.4318)
							(mid -0.402042 -0.402042)
							(end -0.4318 -0.3302)
						)
						(arc
							(start -0.4318 0.3302)
							(mid -0.402042 0.402042)
							(end -0.3302 0.4318)
						)
						(arc
							(start 0.3302 0.4318)
							(mid 0.402042 0.402042)
							(end 0.4318 0.3302)
						)
						(arc
							(start 0.4318 -0.3302)
							(mid 0.402042 -0.402042)
							(end 0.3302 -0.4318)
						)
					)
					(width 0)
					(fill yes)
				)
			)
		)
	)
	(footprint ""
		(layer "F.Cu")
		(at 144.7038 -33.45942 180)
		(property "Reference" "R634"
			(at 0 0 180)
			(layer "F.SilkS")
			(hide yes)
			(effects
				(font
					(size 1.27 1.27)
				)
			)
		)
		(property "Value" "0R2J-2-GP"
			(at 0.064008 -3.993896 180)
			(unlocked yes)
			(layer "F.Fab")
			(hide yes)
			(effects
				(font
					(size 1.016 1.016)
					(thickness 0.1524)
				)
			)
		)
		(property "Device Type" "R402H16"
			(at 0.064008 -5.517896 180)
			(unlocked yes)
			(layer "F.Fab")
			(hide yes)
			(effects
				(font
					(size 1.016 1.016)
					(thickness 0.1524)
				)
			)
		)
		(duplicate_pad_numbers_are_jumpers no)
		(fp_line
			(start 0.508 -0.9398)
			(end -0.508 -0.9398)
			(stroke
				(width 0.1524)
				(type default)
			)
			(layer "F.SilkS")
		)
		(fp_line
			(start -0.508 -0.9398)
			(end -0.508 0.9398)
			(stroke
				(width 0.1524)
				(type default)
			)
			(layer "F.SilkS")
		)
		(fp_rect
			(start -0.508 0.9398)
			(end 0.508 -0.9398)
			(stroke
				(width 0)
				(type default)
			)
			(fill no)
			(layer "F.CrtYd")
		)
		(fp_rect
			(start -0.508 0.9398)
			(end 0.508 -0.9398)
			(stroke
				(width 0)
				(type default)
			)
			(fill no)
			(layer "F.Fab")
		)
		(pad "1" smd custom
			(at 0 -0.4445 180)
			(size 0.1397 0.1397)
			(layers "F.Cu" "F.Mask" "F.Paste")
			(net "8644_USB_DP2")
			(options
				(clearance outline)
				(anchor circle)
			)
			(primitives
				(gr_poly
					(pts
						(arc
							(start -0.1778 -0.2794)
							(mid -0.249642 -0.249642)
							(end -0.2794 -0.1778)
						)
						(arc
							(start -0.2794 0.1778)
							(mid -0.249642 0.249642)
							(end -0.1778 0.2794)
						)
						(arc
							(start 0.1778 0.2794)
							(mid 0.249642 0.249642)
							(end 0.2794 0.1778)
						)
						(arc
							(start 0.2794 -0.1778)
							(mid 0.249642 -0.249642)
							(end 0.1778 -0.2794)
						)
					)
					(width 0)
					(fill yes)
				)
			)
		)
		(pad "2" smd custom
			(at 0 0.4445 180)
			(size 0.1397 0.1397)
			(layers "F.Cu" "F.Mask" "F.Paste")
			(net "P3V3_STBY")
			(options
				(clearance outline)
				(anchor circle)
			)
			(primitives
				(gr_poly
					(pts
						(arc
							(start -0.1778 -0.2794)
							(mid -0.249642 -0.249642)
							(end -0.2794 -0.1778)
						)
						(arc
							(start -0.2794 0.1778)
							(mid -0.249642 0.249642)
							(end -0.1778 0.2794)
						)
						(arc
							(start 0.1778 0.2794)
							(mid 0.249642 0.249642)
							(end 0.2794 0.1778)
						)
						(arc
							(start 0.2794 -0.1778)
							(mid 0.249642 -0.249642)
							(end 0.1778 -0.2794)
						)
					)
					(width 0)
					(fill yes)
				)
			)
		)
	)
	(footprint ""
		(layer "F.Cu")
		(at 324.8406 -93.0656)
		(property "Reference" "U203"
			(at 0 0 0)
			(layer "F.SilkS")
			(hide yes)
			(effects
				(font
					(size 1.27 1.27)
				)
			)
		)
		(property "Value" "MAX7311AUG-GP"
			(at 0 -12.1412 0)
			(unlocked yes)
			(layer "F.Fab")
			(hide yes)
			(effects
				(font
					(size 1.016 1.016)
					(thickness 0.1524)
				)
			)
		)
		(property "Device Type" "TSOIC24H44"
			(at 0 -13.6652 0)
			(unlocked yes)
			(layer "F.Fab")
			(hide yes)
			(effects
				(font
					(size 1.016 1.016)
					(thickness 0.1524)
				)
			)
		)
		(duplicate_pad_numbers_are_jumpers no)
		(fp_line
			(start -4.1148 -1.778)
			(end -4.1148 1.778)
			(stroke
				(width 0.1524)
				(type default)
			)
			(layer "F.SilkS")
		)
		(fp_line
			(start -4.1148 -1.778)
			(end 3.683 -1.778)
			(stroke
				(width 0.1524)
				(type default)
			)
			(layer "F.SilkS")
		)
		(fp_line
			(start -4.0386 1.778)
			(end -4.0386 3.556)
			(stroke
				(width 0.3556)
				(type default)
			)
			(layer "F.SilkS")
		)
		(fp_line
			(start -3.8354 0)
			(end -4.1148 -0.2794)
			(stroke
				(width 0.1524)
				(type default)
			)
			(layer "F.SilkS")
		)
		(fp_line
			(start -3.8354 0)
			(end -4.1148 0.2794)
			(stroke
				(width 0.1524)
				(type default)
			)
			(layer "F.SilkS")
		)
		(fp_line
			(start 3.683 -1.778)
			(end 3.683 1.778)
			(stroke
				(width 0.1524)
				(type default)
			)
			(layer "F.SilkS")
		)
		(fp_line
			(start 3.683 1.778)
			(end -4.1148 1.778)
			(stroke
				(width 0.1524)
				(type default)
			)
			(layer "F.SilkS")
		)
		(fp_poly
			(pts
				(xy -3.7592 -1.778) (xy 3.683 -1.778) (xy 3.683 1.778) (xy -3.7592 1.778)
			)
			(stroke
				(width 0)
				(type default)
			)
			(fill yes)
			(layer "F.SilkS")
		)
		(fp_poly
			(pts
				(xy -4.22656 3.81) (xy 4.22656 3.81) (xy 4.22656 -3.81) (xy -4.22656 -3.81)
			)
			(stroke
				(width 0)
				(type default)
			)
			(fill no)
			(layer "F.CrtYd")
		)
		(fp_poly
			(pts
				(xy -4.22656 -3.81) (xy 4.22656 -3.81) (xy 4.22656 3.81) (xy -4.22656 3.81)
			)
			(stroke
				(width 0)
				(type default)
			)
			(fill no)
			(layer "F.Fab")
		)
		(pad "1" smd rect
			(at -3.57632 2.8194)
			(size 0.3556 1.524)
			(layers "F.Cu" "F.Mask" "F.Paste")
			(net "IOEXP_PMC1_INT#")
		)
		(pad "2" smd rect
			(at -2.92608 2.8194)
			(size 0.3556 1.524)
			(layers "F.Cu" "F.Mask" "F.Paste")
			(net "IOEXP_PMC1_AD1")
		)
		(pad "3" smd rect
			(at -2.27584 2.8194)
			(size 0.3556 1.524)
			(layers "F.Cu" "F.Mask" "F.Paste")
			(net "IOEXP_PMC1_AD2")
		)
		(pad "4" smd rect
			(at -1.6256 2.8194)
			(size 0.3556 1.524)
			(layers "F.Cu" "F.Mask" "F.Paste")
			(net "UPLINK1")
		)
		(pad "5" smd rect
			(at -0.97536 2.8194)
			(size 0.3556 1.524)
			(layers "F.Cu" "F.Mask" "F.Paste")
			(net "UPLINK2")
		)
		(pad "6" smd rect
			(at -0.32512 2.8194)
			(size 0.3556 1.524)
			(layers "F.Cu" "F.Mask" "F.Paste")
			(net "UPLINK3")
		)
		(pad "7" smd rect
			(at 0.32512 2.8194)
			(size 0.3556 1.524)
			(layers "F.Cu" "F.Mask" "F.Paste")
			(net "UPLINK4")
		)
		(pad "8" smd rect
			(at 0.97536 2.8194)
			(size 0.3556 1.524)
			(layers "F.Cu" "F.Mask" "F.Paste")
			(net "UPLINK5")
		)
		(pad "9" smd rect
			(at 1.6256 2.8194)
			(size 0.3556 1.524)
			(layers "F.Cu" "F.Mask" "F.Paste")
			(net "UPLINK6")
		)
		(pad "10" smd rect
			(at 2.27584 2.8194)
			(size 0.3556 1.524)
			(layers "F.Cu" "F.Mask" "F.Paste")
			(net "UPLINK7")
		)
		(pad "11" smd rect
			(at 2.92608 2.8194)
			(size 0.3556 1.524)
			(layers "F.Cu" "F.Mask" "F.Paste")
			(net "UPLINK8")
		)
		(pad "12" smd rect
			(at 3.57632 2.8194)
			(size 0.3556 1.524)
			(layers "F.Cu" "F.Mask" "F.Paste")
			(net "GND")
		)
		(pad "13" smd rect
			(at 3.57632 -2.8194)
			(size 0.3556 1.524)
			(layers "F.Cu" "F.Mask" "F.Paste")
			(net "VS1_LED")
		)
		(pad "14" smd rect
			(at 2.92608 -2.8194)
			(size 0.3556 1.524)
			(layers "F.Cu" "F.Mask" "F.Paste")
			(net "VS2_LED")
		)
		(pad "15" smd rect
			(at 2.27584 -2.8194)
			(size 0.3556 1.524)
			(layers "F.Cu" "F.Mask" "F.Paste")
			(net "VS3_LED")
		)
		(pad "16" smd rect
			(at 1.6256 -2.8194)
			(size 0.3556 1.524)
			(layers "F.Cu" "F.Mask" "F.Paste")
			(net "VS4_LED")
		)
		(pad "17" smd rect
			(at 0.97536 -2.8194)
			(size 0.3556 1.524)
			(layers "F.Cu" "F.Mask" "F.Paste")
			(net "VS5_LED")
		)
		(pad "18" smd rect
			(at 0.32512 -2.8194)
			(size 0.3556 1.524)
			(layers "F.Cu" "F.Mask" "F.Paste")
			(net "VS6_LED")
		)
		(pad "19" smd rect
			(at -0.32512 -2.8194)
			(size 0.3556 1.524)
			(layers "F.Cu" "F.Mask" "F.Paste")
			(net "MAX7311_TP301")
		)
		(pad "20" smd rect
			(at -0.97536 -2.8194)
			(size 0.3556 1.524)
			(layers "F.Cu" "F.Mask" "F.Paste")
			(net "IOEXP_PEWAKE#")
		)
		(pad "21" smd rect
			(at -1.6256 -2.8194)
			(size 0.3556 1.524)
			(layers "F.Cu" "F.Mask" "F.Paste")
			(net "IOEXP_PMC1_AD0")
		)
		(pad "22" smd rect
			(at -2.27584 -2.8194)
			(size 0.3556 1.524)
			(layers "F.Cu" "F.Mask" "F.Paste")
			(net "IOEXP_TWI_SCL3")
		)
		(pad "23" smd rect
			(at -2.92608 -2.8194)
			(size 0.3556 1.524)
			(layers "F.Cu" "F.Mask" "F.Paste")
			(net "IOEXP_TWI_SDA3")
		)
		(pad "24" smd rect
			(at -3.57632 -2.8194)
			(size 0.3556 1.524)
			(layers "F.Cu" "F.Mask" "F.Paste")
			(net "P3V3_STBY")
		)
	)
	(footprint ""
		(layer "F.Cu")
		(at 61.595 -133.985)
		(property "Reference" "R321"
			(at 0 0 0)
			(layer "F.SilkS")
			(hide yes)
			(effects
				(font
					(size 1.27 1.27)
				)
			)
		)
		(property "Value" "0R2J-2-GP"
			(at 0.064008 -3.993896 0)
			(unlocked yes)
			(layer "F.Fab")
			(hide yes)
			(effects
				(font
					(size 1.016 1.016)
					(thickness 0.1524)
				)
			)
		)
		(property "Device Type" "R402H16"
			(at 0.064008 -5.517896 0)
			(unlocked yes)
			(layer "F.Fab")
			(hide yes)
			(effects
				(font
					(size 1.016 1.016)
					(thickness 0.1524)
				)
			)
		)
		(duplicate_pad_numbers_are_jumpers no)
		(fp_line
			(start -0.508 -0.9398)
			(end -0.508 0.9398)
			(stroke
				(width 0.1524)
				(type default)
			)
			(layer "F.SilkS")
		)
		(fp_line
			(start 0.508 -0.9398)
			(end -0.508 -0.9398)
			(stroke
				(width 0.1524)
				(type default)
			)
			(layer "F.SilkS")
		)
		(fp_rect
			(start -0.508 0.9398)
			(end 0.508 -0.9398)
			(stroke
				(width 0)
				(type default)
			)
			(fill no)
			(layer "F.CrtYd")
		)
		(fp_rect
			(start -0.508 0.9398)
			(end 0.508 -0.9398)
			(stroke
				(width 0)
				(type default)
			)
			(fill no)
			(layer "F.Fab")
		)
		(pad "1" smd custom
			(at 0 -0.4445)
			(size 0.1397 0.1397)
			(layers "F.Cu" "F.Mask" "F.Paste")
			(net "ADC_P0V9")
			(options
				(clearance outline)
				(anchor circle)
			)
			(primitives
				(gr_poly
					(pts
						(arc
							(start -0.1778 -0.2794)
							(mid -0.249642 -0.249642)
							(end -0.2794 -0.1778)
						)
						(arc
							(start -0.2794 0.1778)
							(mid -0.249642 0.249642)
							(end -0.1778 0.2794)
						)
						(arc
							(start 0.1778 0.2794)
							(mid 0.249642 0.249642)
							(end 0.2794 0.1778)
						)
						(arc
							(start 0.2794 -0.1778)
							(mid 0.249642 -0.249642)
							(end 0.1778 -0.2794)
						)
					)
					(width 0)
					(fill yes)
				)
			)
		)
		(pad "2" smd custom
			(at 0 0.4445)
			(size 0.1397 0.1397)
			(layers "F.Cu" "F.Mask" "F.Paste")
			(net "ADC_P0V9_BMC")
			(options
				(clearance outline)
				(anchor circle)
			)
			(primitives
				(gr_poly
					(pts
						(arc
							(start -0.1778 -0.2794)
							(mid -0.249642 -0.249642)
							(end -0.2794 -0.1778)
						)
						(arc
							(start -0.2794 0.1778)
							(mid -0.249642 0.249642)
							(end -0.1778 0.2794)
						)
						(arc
							(start 0.1778 0.2794)
							(mid 0.249642 0.249642)
							(end 0.2794 0.1778)
						)
						(arc
							(start 0.2794 -0.1778)
							(mid 0.249642 -0.249642)
							(end 0.1778 -0.2794)
						)
					)
					(width 0)
					(fill yes)
				)
			)
		)
	)
	(footprint ""
		(layer "F.Cu")
		(at 190.392304 -212.420454 180)
		(property "Reference" "C123"
			(at 0 0 180)
			(layer "F.SilkS")
			(hide yes)
			(effects
				(font
					(size 1.27 1.27)
				)
			)
		)
		(property "Value" "SCD22U10V2KX-1GP"
			(at 1.1811 -2.7051 180)
			(unlocked yes)
			(layer "F.Fab")
			(hide yes)
			(effects
				(font
					(size 1.016 1.016)
					(thickness 0.1524)
				)
			)
		)
		(property "Device Type" "C402H22"
			(at 1.1811 -4.2291 180)
			(unlocked yes)
			(layer "F.Fab")
			(hide yes)
			(effects
				(font
					(size 1.016 1.016)
					(thickness 0.1524)
				)
			)
		)
		(duplicate_pad_numbers_are_jumpers no)
		(fp_rect
			(start -0.4318 0.9525)
			(end 0.4318 -0.9525)
			(stroke
				(width 0)
				(type default)
			)
			(fill no)
			(layer "F.CrtYd")
		)
		(fp_rect
			(start -0.4318 0.9525)
			(end 0.4318 -0.9525)
			(stroke
				(width 0)
				(type default)
			)
			(fill no)
			(layer "F.Fab")
		)
		(pad "1" smd custom
			(at 0 -0.4445 180)
			(size 0.1524 0.1524)
			(layers "F.Cu" "F.Mask" "F.Paste")
			(net "PCIE_TX_CAP_P45")
			(options
				(clearance outline)
				(anchor circle)
			)
			(primitives
				(gr_poly
					(pts
						(arc
							(start 0.3048 -0.2032)
							(mid 0.275042 -0.275042)
							(end 0.2032 -0.3048)
						)
						(arc
							(start -0.2032 -0.3048)
							(mid -0.275042 -0.275042)
							(end -0.3048 -0.2032)
						)
						(arc
							(start -0.3048 0.2032)
							(mid -0.275042 0.275042)
							(end -0.2032 0.3048)
						)
						(arc
							(start 0.2032 0.3048)
							(mid 0.275042 0.275042)
							(end 0.3048 0.2032)
						)
					)
					(width 0)
					(fill yes)
				)
			)
		)
		(pad "2" smd custom
			(at 0 0.4445 180)
			(size 0.1524 0.1524)
			(layers "F.Cu" "F.Mask" "F.Paste")
			(net "PCIE_TX_P45")
			(options
				(clearance outline)
				(anchor circle)
			)
			(primitives
				(gr_poly
					(pts
						(arc
							(start 0.3048 -0.2032)
							(mid 0.275042 -0.275042)
							(end 0.2032 -0.3048)
						)
						(arc
							(start -0.2032 -0.3048)
							(mid -0.275042 -0.275042)
							(end -0.3048 -0.2032)
						)
						(arc
							(start -0.3048 0.2032)
							(mid -0.275042 0.275042)
							(end -0.2032 0.3048)
						)
						(arc
							(start 0.2032 0.3048)
							(mid 0.275042 0.275042)
							(end 0.3048 0.2032)
						)
					)
					(width 0)
					(fill yes)
				)
			)
		)
	)
)
